# S9S_MB_2U (Grand Teton) — schematic netlist excerpt (pin names and nets, part order shuffled) for the footprints in the layout excerpt that follows; sources: Cadence DE-HDL packaged netlist, KiCad conversion of 03242023_DA0F0TMBIJ0_F0T_Motherboard_J_brd_V01_OCP.brd

R3899  Q_RES  49.9 1% CHIP  pkg 0402LF  page 106 : A = I3C_SPD_DDREFGH_CPU1_LVC1_SCL_R ; B = I3C_SPD_DDREFGH_CPU1_LVC1_SCL
C1943  Q_CAP  0.1UF 25V 10% X7R  pkg 0402  page 217 : A = VCC_PLD_CORE ; B = GND

(kicad_pcb
	(version 20260206)
	(generator "pcbnew")
	(generator_version "10.0")
	(general
		(thickness 1.6)
		(legacy_teardrops no)
	)
	(paper "A4")
	(title_block
		(title "03242023_DA0F0TMBIJ0_F0T_Motherboard_J_brd_V01_OCP.brd")
		(comment 1 "Grand Teton / footprints 5583-5584 of 6105")
	)
	(layers
		(0 "F.Cu" signal "TOP")
		(4 "In1.Cu" signal "GND")
		(6 "In2.Cu" signal "IN1")
		(8 "In3.Cu" signal "GND1")
		(10 "In4.Cu" signal "IN2")
		(12 "In5.Cu" signal "GND2")
		(14 "In6.Cu" signal "IN3")
		(16 "In7.Cu" signal "GND3")
		(18 "In8.Cu" signal "VCC")
		(20 "In9.Cu" signal "VCC1")
		(22 "In10.Cu" signal "GND4")
		(24 "In11.Cu" signal "IN4")
		(26 "In12.Cu" signal "GND5")
		(28 "In13.Cu" signal "IN5")
		(30 "In14.Cu" signal "GND6")
		(32 "In15.Cu" signal "IN6")
		(34 "In16.Cu" signal "GND7")
		(2 "B.Cu" signal "BOTTOM")
		(9 "F.Adhes" user "F.Adhesive")
		(11 "B.Adhes" user "B.Adhesive")
		(13 "F.Paste" user "Package Geometry/Pastemask Top")
		(15 "B.Paste" user "Package Geometry/Pastemask Bottom")
		(5 "F.SilkS" user "Ref Des/Silkscreen Top")
		(7 "B.SilkS" user "Ref Des/Silkscreen Bottom")
		(1 "F.Mask" user "Board Geometry/Soldermask Top")
		(3 "B.Mask" user "Board Geometry/Soldermask Bottom")
		(17 "Dwgs.User" user "User.Drawings")
		(19 "Cmts.User" user "User.Comments")
		(21 "Eco1.User" user "User.Eco1")
		(23 "Eco2.User" user "User.Eco2")
		(25 "Edge.Cuts" user "Board Geometry/Outline")
		(27 "Margin" user)
		(31 "F.CrtYd" user "Package Geometry/Place Bound Top")
		(29 "B.CrtYd" user "Package Geometry/Place Bound Bottom")
		(35 "F.Fab" user "Ref Des/Assembly Top")
		(33 "B.Fab" user "Ref Des/Assembly Bottom")
	)
	(footprint ""
		(layer "B.Cu")
		(at 166.165784 -316.592458 90)
		(property "Reference" "R3899"
			(at 0 0 90)
			(layer "B.SilkS")
			(hide yes)
			(effects
				(font
					(size 1.27 1.27)
				)
				(justify mirror)
			)
		)
		(property "Value" ""
			(at 0 0 90)
			(layer "B.Fab")
			(effects
				(font
					(size 1.27 1.27)
				)
				(justify mirror)
			)
		)
		(duplicate_pad_numbers_are_jumpers no)
		(fp_line
			(start 0.7874 -0.4064)
			(end -0.7874 -0.4064)
			(stroke
				(width 0.1524)
				(type default)
			)
			(layer "B.SilkS")
		)
		(fp_line
			(start -0.7874 -0.4064)
			(end -0.7874 0.4064)
			(stroke
				(width 0.1524)
				(type default)
			)
			(layer "B.SilkS")
		)
		(fp_line
			(start 0.7874 0.4064)
			(end 0.7874 -0.4064)
			(stroke
				(width 0.1524)
				(type default)
			)
			(layer "B.SilkS")
		)
		(fp_line
			(start -0.7874 0.4064)
			(end 0.7874 0.4064)
			(stroke
				(width 0.1524)
				(type default)
			)
			(layer "B.SilkS")
		)
		(fp_line
			(start 0.67945 -0.305054)
			(end 0.12065 -0.305054)
			(stroke
				(width 0.1)
				(type default)
			)
			(layer "B.Fab")
		)
		(fp_line
			(start 0.12065 -0.305054)
			(end 0.12065 -0.2794)
			(stroke
				(width 0.1)
				(type default)
			)
			(layer "B.Fab")
		)
		(fp_line
			(start -0.12065 -0.3048)
			(end -0.67945 -0.3048)
			(stroke
				(width 0.1)
				(type default)
			)
			(layer "B.Fab")
		)
		(fp_line
			(start -0.67945 -0.3048)
			(end -0.67945 0.3048)
			(stroke
				(width 0.1)
				(type default)
			)
			(layer "B.Fab")
		)
		(fp_line
			(start 0.12065 -0.2794)
			(end -0.12065 -0.2794)
			(stroke
				(width 0.1)
				(type default)
			)
			(layer "B.Fab")
		)
		(fp_line
			(start -0.12065 -0.2794)
			(end -0.12065 -0.3048)
			(stroke
				(width 0.1)
				(type default)
			)
			(layer "B.Fab")
		)
		(fp_line
			(start 0.12065 0.2794)
			(end 0.12065 0.3048)
			(stroke
				(width 0.1)
				(type default)
			)
			(layer "B.Fab")
		)
		(fp_line
			(start -0.120396 0.2794)
			(end 0.12065 0.2794)
			(stroke
				(width 0.1)
				(type default)
			)
			(layer "B.Fab")
		)
		(fp_line
			(start 0.67945 0.3048)
			(end 0.67945 -0.305054)
			(stroke
				(width 0.1)
				(type default)
			)
			(layer "B.Fab")
		)
		(fp_line
			(start 0.12065 0.3048)
			(end 0.67945 0.3048)
			(stroke
				(width 0.1)
				(type default)
			)
			(layer "B.Fab")
		)
		(fp_line
			(start -0.120396 0.3048)
			(end -0.120396 0.2794)
			(stroke
				(width 0.1)
				(type default)
			)
			(layer "B.Fab")
		)
		(fp_line
			(start -0.67945 0.3048)
			(end -0.120396 0.3048)
			(stroke
				(width 0.1)
				(type default)
			)
			(layer "B.Fab")
		)
		(pad "1" smd circle
			(at 0.40005 0 270)
			(size 0 0)
			(layers "B.Cu" "B.Mask" "B.Paste")
			(net "I3C_SPD_DDREFGH_CPU1_LVC1_SCL_R")
		)
		(pad "2" smd circle
			(at -0.40005 0 270)
			(size 0 0)
			(layers "B.Cu" "B.Mask" "B.Paste")
			(net "I3C_SPD_DDREFGH_CPU1_LVC1_SCL")
		)
	)
	(footprint ""
		(layer "B.Cu")
		(at 180.26888 -123.154948 180)
		(property "Reference" "C1943"
			(at 0 0 0)
			(layer "B.SilkS")
			(hide yes)
			(effects
				(font
					(size 1.27 1.27)
				)
				(justify mirror)
			)
		)
		(property "Value" ""
			(at 0 0 0)
			(layer "B.Fab")
			(effects
				(font
					(size 1.27 1.27)
				)
				(justify mirror)
			)
		)
		(duplicate_pad_numbers_are_jumpers no)
		(fp_line
			(start 0.7874 0.4064)
			(end 0.7874 -0.4064)
			(stroke
				(width 0.1524)
				(type default)
			)
			(layer "B.SilkS")
		)
		(fp_line
			(start 0.7874 -0.4064)
			(end -0.7874 -0.4064)
			(stroke
				(width 0.1524)
				(type default)
			)
			(layer "B.SilkS")
		)
		(fp_line
			(start -0.7874 0.4064)
			(end 0.7874 0.4064)
			(stroke
				(width 0.1524)
				(type default)
			)
			(layer "B.SilkS")
		)
		(fp_line
			(start -0.7874 -0.4064)
			(end -0.7874 0.4064)
			(stroke
				(width 0.1524)
				(type default)
			)
			(layer "B.SilkS")
		)
		(fp_line
			(start 0.67945 0.3048)
			(end 0.67945 -0.305054)
			(stroke
				(width 0.1)
				(type default)
			)
			(layer "B.Fab")
		)
		(fp_line
			(start 0.67945 -0.305054)
			(end 0.12065 -0.305054)
			(stroke
				(width 0.1)
				(type default)
			)
			(layer "B.Fab")
		)
		(fp_line
			(start 0.12065 0.3048)
			(end 0.67945 0.3048)
			(stroke
				(width 0.1)
				(type default)
			)
			(layer "B.Fab")
		)
		(fp_line
			(start 0.12065 0.2794)
			(end 0.12065 0.3048)
			(stroke
				(width 0.1)
				(type default)
			)
			(layer "B.Fab")
		)
		(fp_line
			(start 0.12065 -0.2794)
			(end -0.12065 -0.2794)
			(stroke
				(width 0.1)
				(type default)
			)
			(layer "B.Fab")
		)
		(fp_line
			(start 0.12065 -0.305054)
			(end 0.12065 -0.2794)
			(stroke
				(width 0.1)
				(type default)
			)
			(layer "B.Fab")
		)
		(fp_line
			(start -0.120396 0.3048)
			(end -0.120396 0.2794)
			(stroke
				(width 0.1)
				(type default)
			)
			(layer "B.Fab")
		)
		(fp_line
			(start -0.120396 0.2794)
			(end 0.12065 0.2794)
			(stroke
				(width 0.1)
				(type default)
			)
			(layer "B.Fab")
		)
		(fp_line
			(start -0.12065 -0.2794)
			(end -0.12065 -0.3048)
			(stroke
				(width 0.1)
				(type default)
			)
			(layer "B.Fab")
		)
		(fp_line
			(start -0.12065 -0.3048)
			(end -0.67945 -0.3048)
			(stroke
				(width 0.1)
				(type default)
			)
			(layer "B.Fab")
		)
		(fp_line
			(start -0.67945 0.3048)
			(end -0.120396 0.3048)
			(stroke
				(width 0.1)
				(type default)
			)
			(layer "B.Fab")
		)
		(fp_line
			(start -0.67945 -0.3048)
			(end -0.67945 0.3048)
			(stroke
				(width 0.1)
				(type default)
			)
			(layer "B.Fab")
		)
		(pad "1" smd circle
			(at 0.40005 0)
			(size 0 0)
			(layers "B.Cu" "B.Mask" "B.Paste")
			(net "VCC_PLD_CORE")
		)
		(pad "2" smd circle
			(at -0.40005 0)
			(size 0 0)
			(layers "B.Cu" "B.Mask" "B.Paste")
			(net "GND")
		)
	)
)
